# S9S_MB_2U (Grand Teton) — schematic parts with pin connectivity, parts 3950–4106 of 6093; source: Cadence DE-HDL packaged netlist (pstxprt.dat, pstxnet.dat, pstchip.dat)

R1297  Q_RES  0 5% CHIP  pkg 0402LF  page 197 : 1 = PECI_BMC_R ; 2 = PECI_BMC_B1
R1298  Q_RES  1K 1% EMPTY  pkg 0402LF  page 200 : 1 = P1V05_PCH_AUX ; 2 = FM_MFG_MODE
R1299  Q_RES  10K 1% CHIP  pkg 0402LF  page 200 : 1 = FM_MFG_MODE ; 2 = GND
R1300  Q_RES  33.2 1% CHIP  pkg 0402LF  page 205 : 1 = FM_BIOS_POST_CMPLT_N ; 2 = FM_BIOS_POST_CMPLT_BMC_N
R1302  Q_RES  2K 1% EMPTY  pkg 0402LF  page 219 : 1 = PWRGD_DRAMPWRGD_CPU0_AB_R_LVC1 ; 2 = GND
R1305  Q_RES  10K 1% EMPTY  pkg 0402LF  page 208 : 1 = P3V3_AUX ; 2 = FM_PLD_CLKS_DEV_EN
R1306  Q_RES  33.2 1% CHIP  pkg 0402LF  page 205 : 1 = FM_PS_PWROK_DLY_R_SEL ; 2 = FM_PS_PWROK_DLY_SEL
R1307  Q_RES  33.2 1% CHIP  pkg 0402LF  page 205 : 1 = FM_THROTTLE_N ; 2 = FM_THROTTLE_R_N
R1308  Q_RES  10K 1% EMPTY  pkg 0402LF  page 220 : 1 = FM_RST_PERST_BIT1 ; 2 = GND
R1309  Q_RES  33.2 1% CHIP  pkg 0402LF  page 205 : 1 = IRQ_SMI_ACTIVE_N ; 2 = IRQ_SMI_ACTIVE_BMC_N
R1310  Q_RES  33.2 1% CHIP  pkg 0402LF  page 205 : 1 = IRQ_PCH_CPU_NMI_EVENT_R_N ; 2 = IRQ_PCH_CPU_NMI_EVENT_N
R1311  Q_RES  10K 1% CHIP  pkg 0402LF  page 200 : 1 = FM_XTAL_INPUT_FREQUENCY_0_MGPIO ; 2 = GND
R1312  Q_RES  10K 1% EMPTY  pkg 0402LF  page 220 : 1 = FM_RST_PERST_BIT2 ; 2 = GND
R1313  Q_RES  33.2 1% CHIP  pkg 0402LF  page 205 : 1 = FM_PCH_GLB_RST_WARN_N ; 2 = FM_PCH_PLD_GLB_RST_WARN_N
R1316  Q_RES  200K 0.1% EMPTY  pkg 0603LF  page 179 : 1 = XTAL_PCH_25M_IN_R ; 2 = XTAL_PCH_25M_OUT
R1317  Q_RES  1K 1% CHIP  pkg 0402LF  page 201 : 1 = P1V05_PCH_AUX ; 2 = PU_BIOS_RCVR_BOOT
R1318  Q_RES  0 5% CHIP  pkg 0402LF  page 223 : 1 = FM_THERMTRIP_DLY_LVC1_R_N ; 2 = FM_THERMTRIP_DLY_LVC1_N
R1319  Q_RES  2K 1% EMPTY  pkg 0402LF  page 241 : 1 = SMB_HOST_3V3AUX_SCL ; 2 = P3V3_AUX
R1320  Q_RES  1K 1% CHIP  pkg 0402LF  page 201 : 1 = P3V3_AUX ; 2 = PU_SWAP_OVERRIDE_N
R1324  Q_RES  1K 1% CHIP  pkg 0402LF  page 201 : 1 = GND ; 2 = PD_BIOS_IMAGE_SWAP_N
R1325  Q_RES  1K 1% CHIP  pkg 0402LF  page 201 : 1 = P3V3_AUX ; 2 = PU_FLASH_SECURITY_STRAP
R1326  Q_RES  2K 1% EMPTY  pkg 0402LF  page 219 : 1 = PWRGD_DRAMPWRGD_CPU0_CD_R_LVC1 ; 2 = GND
R1327  Q_RES  2K 1% EMPTY  pkg 0402LF  page 219 : 1 = PWRGD_DRAMPWRGD_CPU0_EF_R_LVC1 ; 2 = GND
R1328  Q_RES  2K 1% EMPTY  pkg 0402LF  page 219 : 1 = PWRGD_DRAMPWRGD_CPU0_GH_R_LVC1 ; 2 = GND
R1329  Q_RES  2K 1% EMPTY  pkg 0402LF  page 219 : 1 = PWRGD_DRAMPWRGD_CPU1_AB_R_LVC1 ; 2 = GND
R1330  Q_RES  2K 1% EMPTY  pkg 0402LF  page 219 : 1 = PWRGD_DRAMPWRGD_CPU1_CD_R_LVC1 ; 2 = GND
R1331  Q_RES  4.7K 5% EMPTY  pkg 0402LF  page 243 : 1 = P3V3_AUX ; 2 = SMB_FRU_3V3AUX_SCL
R1332  Q_RES  4.7K 5% EMPTY  pkg 0402LF  page 243 : 1 = P3V3_AUX ; 2 = SMB_FRU_3V3AUX_SDA
R1333  Q_RES  1K 1% CHIP  pkg 0402LF  page 201 : 1 = GND ; 2 = PD_RST_RTCRST_N
R1335  Q_RES  1K 1% CHIP  pkg 0402LF  page 201 : 1 = GND ; 2 = PD_PASSWORD_CLEAR
R1336  Q_RES  2.2K 5% EMPTY  pkg 0402LF  page 241 : 1 = I3C_BMC_SWB_SCL ; 2 = P3V3_AUX
R1338  Q_RES  10K 1% CHIP  pkg 0402LF  page 201 : 1 = FM_PCH_BIOS_RCVR_MODE ; 2 = GND
R1339  Q_RES  10K 1% CHIP  pkg 0402LF  page 201 : 1 = P3V3_AUX ; 2 = FM_BIOS_IMAGE_SWAP_N
R1340  Q_RES  20K 1% CHIP  pkg 0402LF  page 201 : 1 = P3V3_RTC_AUX ; 2 = RST_RTCRST_N
R1341  Q_RES  10K 1% CHIP  pkg 0402LF  page 201 : 1 = FM_ADR_COMPLETE ; 2 = GND
R1342  Q_RES  10K 1% CHIP  pkg 0402LF  page 201 : 1 = P1V05_PCH_AUX ; 2 = FM_ME_RCVR_N
R1343  Q_RES  10K 1% CHIP  pkg 0402LF  page 201 : 1 = P1V05_PCH_AUX ; 2 = FM_PASSWORD_CLEAR_N
R1345  Q_RES  0 5% CHIP  pkg 0402LF  page 239 : 1 = JTAG_BMC_DBP_TDI_R ; 2 = JTAG_BMC_DBP_TDI
R1346  Q_RES  100 1% CHIP  pkg 0402LF  page 239 : 1 = P0V7_JTAG_VREF_2 ; 2 = GND
R1347  Q_RES  1K 1% CHIP  pkg 0402LF  page 239 : 1 = PD_GTL2014_BMC_JTAG_VREF_1 ; 2 = GND
R1348  Q_RES  0 5% CHIP  pkg 0402LF  page 134 : 1 = JTAG_DBP_CPU_GTL_TCK_R1 ; 2 = JTAG_DBP_CPU_GTL_TCK
R1349  Q_RES  0 5% CHIP  pkg 0402LF  page 134 : 1 = JTAG_DBP_TCK_PCH_R ; 2 = JTAG_DBP_TCK_PCH
R1350  Q_RES  100K 1% CHIP  pkg 0402LF  page 154 : 1 = RMII_OCP_BMC_CRSDV ; 2 = GND
R1351  Q_RES  100K 1% CHIP  pkg 0402LF  page 154 : 1 = RMII_OCP_BMC_RXD_0 ; 2 = GND
R1352  Q_RES  100K 1% CHIP  pkg 0402LF  page 154 : 1 = RMII_OCP_BMC_RXD_1 ; 2 = GND
R1353  Q_RES  100K 1% CHIP  pkg 0402LF  page 154 : 1 = RMII_BMC_OCP_TX_EN ; 2 = GND
R1354  Q_RES  100K 1% CHIP  pkg 0402LF  page 154 : 1 = RMII_BMC_OCP_TXD_0 ; 2 = GND
R1355  Q_RES  100K 1% CHIP  pkg 0402LF  page 154 : 1 = RMII_BMC_OCP_TXD_1 ; 2 = GND
R1356  Q_RES  1K 1% CHIP  pkg 0402LF  page 154 : 1 = RMII_BMC_OCP_RX_ER ; 2 = GND
R1365  Q_RES  1K 1% CHIP  pkg 0402LF  page 134 : 1 = FM_JTAG_TCK_MUX_SEL ; 2 = GND
R1366  Q_RES  100 1% CHIP  pkg 0402LF  page 239 : 1 = JTAG_DBP_TDO ; 2 = JTAG_DBP_FB_TDO
R1367  Q_RES  100 1% CHIP  pkg 0402LF  page 239 : 1 = JTAG_DBP_PRDY_N ; 2 = JTAG_DBP_PRDY_R_N
R1368  Q_RES  1K 1% CHIP  pkg 0402LF  page 239 : 1 = PD_JTAG_DBP_B2 ; 2 = GND
R1369  Q_RES  1K 1% CHIP  pkg 0402LF  page 239 : 1 = PD_JTAG_DBP_B0 ; 2 = GND
R1370  Q_RES  100 1% CHIP  pkg 0402LF  page 134 : 1 = P3V3_AUX ; 2 = FM_REMOTE_DEBUG_DET_R
R1371  Q_RES  130 1% CHIP  pkg 0402LF  page 256 : 1 = LED_RST_PLD_CPU0_DRAM_AB_N ; 2 = P3V3_AUX
R1374  Q_RES  1K 1% CHIP  pkg 0402LF  page 134 : 1 = PD_JTAG_BMC_NTRST_N ; 2 = GND
R1375  Q_RES  10K 1% CHIP  pkg 0402LF  page 134 : 1 = FM_BMC_EN_DET ; 2 = GND
R1380  Q_RES  1K 1% CHIP  pkg 0402LF  page 239 : 1 = P3V3_AUX ; 2 = JTAG_BMC_DBP_TDO
R1381  Q_RES  1K 1% CHIP  pkg 0402LF  page 239 : 1 = P3V3_AUX ; 2 = FM_BMC_CPU_FBRK_OUT_N
R1382  Q_RES  1K 1% CHIP  pkg 0402LF  page 239 : 1 = P3V3_AUX ; 2 = JTAG_DBP_BMC_PRDY_N
R1383  Q_RES  1K 1% CHIP  pkg 0402LF  page 239 : 1 = P3V3_AUX ; 2 = JTAG_BMC_DBP_PREQ_N
R1384  Q_RES  2K 1% EMPTY  pkg 0402LF  page 241 : 1 = SMB_SML0_3V3AUX_SCL ; 2 = P3V3_AUX
R1385  Q_RES  2K 1% EMPTY  pkg 0402LF  page 241 : 1 = SMB_SML0_3V3AUX_SDA ; 2 = P3V3_AUX
R1386  Q_RES  2K 1% EMPTY  pkg 0402LF  page 241 : 1 = SMB_SML1_PMBUS_3V3AUX_PCH_SCL ; 2 = P3V3_AUX
R1387  Q_RES  2K 1% EMPTY  pkg 0402LF  page 241 : 1 = SMB_SML1_PMBUS_3V3AUX_PCH_SDA ; 2 = P3V3_AUX
R1388  Q_RES  2K 1% EMPTY  pkg 0402LF  page 219 : 1 = PWRGD_DRAMPWRGD_CPU1_EF_R_LVC1 ; 2 = GND
R1389  Q_RES  0 5% CHIP  pkg 0402LF  page 262 : 1 = FM_P1V05_PCH_AUX_EN ; 2 = FM_P1V05_PCH_AUX_R_EN
R1390  Q_RES  1K 1% EMPTY  pkg 0402LF  page 208 : 1 = FM_PLD_CLKS_DEV_EN ; 2 = GND
R1391  Q_RES  240 1% EMPTY  pkg 0402LF  page 120 : 1 = GND ; 2 = FM_S3M_CPU0_LVC1_GPIO_2
R1392  Q_RES  240 1% EMPTY  pkg 0402LF  page 120 : 1 = GND ; 2 = FM_S3M_CPU0_LVC1_GPIO_3
R1393  Q_RES  240 1% EMPTY  pkg 0402LF  page 120 : 1 = GND ; 2 = FM_S3M_CPU1_LVC1_GPIO_2
R1394  Q_RES  240 1% EMPTY  pkg 0402LF  page 120 : 1 = GND ; 2 = FM_S3M_CPU1_LVC1_GPIO_3
R1395  Q_RES  33.2 1% CHIP  pkg 0402LF  page 185 : 1 = SPI_PCH_TPM_CS_N ; 2 = SPI_TPM_CS_N
R1396  Q_RES  10K 1% CHIP  pkg 0402LF  page 190 : 1 = FM_M2_SSD_0_PEDET ; 2 = P3V3_AUX
R1398  Q_RES  2K 1% EMPTY  pkg 0402LF  page 219 : 1 = PWRGD_CPU1_LVC1_R ; 2 = GND
R1399  Q_RES  10K 1% CHIP  pkg 0402LF  page 220 : 1 = FM_PFR_DSW_PWROK_N ; 2 = P3V3_AUX
R1401  Q_RES  10K 1% CHIP  pkg 0402LF  page 220 : 1 = PU_MAIN_FPGA_CONFIG_DONE ; 2 = P3V3_AUX
R1402  Q_RES  2K 1% CHIP  pkg 0402LF  page 219 : 1 = PWRGD_SYS_PWROK ; 2 = GND
R1403  Q_RES  2K 1% CHIP  pkg 0402LF  page 219 : 1 = PWRGD_PCH_PWROK ; 2 = GND
R1404  Q_RES  2K 1% CHIP  pkg 0402LF  page 219 : 1 = FM_PCH_P1V8_AUX_EN ; 2 = GND
R1405  Q_RES  2K 1% CHIP  pkg 0402LF  page 219 : 1 = FM_PVCCIN_CPU0_R_EN ; 2 = GND
R1406  Q_RES  2K 1% CHIP  pkg 0402LF  page 219 : 1 = FM_PVCCIN_CPU1_R_EN ; 2 = GND
R1407  Q_RES  2K 1% CHIP  pkg 0402LF  page 219 : 1 = FM_PVCCINFAON_CPU0_R_EN ; 2 = GND
R1408  Q_RES  2K 1% CHIP  pkg 0402LF  page 219 : 1 = FM_PVCCINFAON_CPU1_R_EN ; 2 = GND
R1409  Q_RES  2K 1% CHIP  pkg 0402LF  page 219 : 1 = FM_PVCCFA_EHV_CPU0_R_EN ; 2 = GND
R1410  Q_RES  2K 1% CHIP  pkg 0402LF  page 219 : 1 = FM_PVCCFA_EHV_CPU1_R_EN ; 2 = GND
R1411  Q_RES  2K 1% CHIP  pkg 0402LF  page 219 : 1 = FM_PVCCFA_EHV_FIVRA_CPU0_R_EN ; 2 = GND
R1412  Q_RES  2K 1% CHIP  pkg 0402LF  page 219 : 1 = FM_PVCCFA_EHV_FIVRA_CPU1_R_EN ; 2 = GND
R1413  Q_RES  2K 1% CHIP  pkg 0402LF  page 219 : 1 = FM_PVCCD_HV_CPU0_EN ; 2 = GND
R1414  Q_RES  2K 1% CHIP  pkg 0402LF  page 219 : 1 = FM_PVCCD_HV_CPU1_EN ; 2 = GND
R1415  Q_RES  2K 1% EMPTY  pkg 0402LF  page 219 : 1 = RST_CPU0_LVC1_R_N ; 2 = GND
R1416  Q_RES  2K 1% EMPTY  pkg 0402LF  page 219 : 1 = RST_CPU1_LVC1_R_N ; 2 = GND
R1417  Q_RES  2K 1% CHIP  pkg 0402LF  page 219 : 1 = RST_PCIE_CPU0_DEV_PERST_N ; 2 = GND
R1418  Q_RES  2K 1% CHIP  pkg 0402LF  page 219 : 1 = RST_PCIE_CPU1_DEV_PERST_N ; 2 = GND
R1419  Q_RES  2K 1% CHIP  pkg 0402LF  page 219 : 1 = RST_PCIE_PCH_DEV_PERST_N ; 2 = GND
R1420  Q_RES  2K 1% CHIP  pkg 0402LF  page 219 : 1 = RST_PLTRST_PLD_B_N ; 2 = GND
R1421  Q_RES  2K 1% CHIP  pkg 0402LF  page 219 : 1 = RST_RSMRST_PLD_R_N ; 2 = GND
R1423  Q_RES  33.2 1% CHIP  pkg 0402LF  page 222 : 1 = PWRGD_SYS_PWROK_R ; 2 = PWRGD_SYS_PWROK
R1434  Q_RES  10K 1% CHIP  pkg 0402LF  page 220 : 1 = FM_SYS_THROTTLE_R_N ; 2 = P3V3_AUX
R1435  Q_RES  10K 1% CHIP  pkg 0402LF  page 220 : 1 = FM_ADR_TRIGGER_N ; 2 = P3V3_AUX
R1437  Q_RES  10K 1% CHIP  pkg 0402LF  page 220 : 1 = FM_PLD_HEARTBEAT_LVC3 ; 2 = P3V3_AUX
R1440  Q_RES  10K 1% EMPTY  pkg 0402LF  page 220 : 1 = JTAG_PLD_TDO_R ; 2 = P3V3_AUX
R1442  Q_RES  33.2 1% CHIP  pkg 0402LF  page 222 : 1 = PWRGD_PCH_PWROK_R ; 2 = PWRGD_PCH_PWROK
R1443  Q_RES  33.2 1% CHIP  pkg 0402LF  page 222 : 1 = PWRGD_CPUPWRGD_LVC1 ; 2 = PWRGD_CPUPWRGD_LVC1_R
R1444  Q_RES  33.2 1% CHIP  pkg 0402LF  page 222 : 1 = PWRGD_P1V8_PCH_AUX ; 2 = PWRGD_P1V8_PCH_AUX_PLD
R1445  Q_RES  2K 1% CHIP  pkg 0402LF  page 282 : 1 = FM_PVNN_MAIN_CPU0_EN ; 2 = GND
R1446  Q_RES  33.2 1% CHIP  pkg 0402LF  page 224 : 1 = PWRGD_PS_PWROK_PLD_ISO ; 2 = PWRGD_PS_PWROK_PLD_ISO_R
R1447  Q_RES  33.2 1% CHIP  pkg 0402LF  page 222 : 1 = FM_CPU0_SKTOCC_LVT3_N ; 2 = FM_CPU0_SKTOCC_LVT3_PLD_N
R1448  Q_RES  33.2 1% CHIP  pkg 0402LF  page 222 : 1 = FM_CPU1_SKTOCC_LVT3_N ; 2 = FM_CPU1_SKTOCC_LVT3_PLD_N
R1449  Q_RES  10K 1% CHIP  pkg 0402LF  page 204 : 1 = P3V3_AUX ; 2 = FM_BIOS_POST_CMPLT_N
R1450  Q_RES  10K 1% CHIP  pkg 0402LF  page 204 : 1 = P3V3_AUX ; 2 = FM_THROTTLE_N
R1451  Q_RES  2K 1% CHIP  pkg 0402LF  page 183 : 1 = PU_SMB_SML3_3V3AUX_PCH_SCL ; 2 = P3V3_AUX
R1452  Q_RES  2K 1% CHIP  pkg 0402LF  page 183 : 1 = PU_SMB_SML3_3V3AUX_PCH_SDA ; 2 = P3V3_AUX
R1453  Q_RES  2K 1% CHIP  pkg 0402LF  page 183 : 1 = PU_SMB_SML4_3V3AUX_PCH_SCL ; 2 = P3V3_AUX
R1454  Q_RES  2K 1% CHIP  pkg 0402LF  page 183 : 1 = PU_SMB_SML4_3V3AUX_PCH_SDA ; 2 = P3V3_AUX
R1455  Q_RES  49.9 1% CHIP  pkg 0402LF  page 205 : 1 = FM_ADR_MODE0_R ; 2 = FM_ADR_MODE0
R1456  Q_RES  49.9 1% CHIP  pkg 0402LF  page 205 : 1 = FM_CPU_RMCA_CATERR_DLY_LVT3_R_N ; 2 = FM_CPU_RMCA_CATERR_DLY_N
R1457  Q_RES  10K 1% CHIP  pkg 0402LF  page 200 : 1 = FM_XTAL_INPUT_FREQUENCY_1_MGPIO ; 2 = GND
R1458  Q_RES  10K 1% CHIP  pkg 0402LF  page 204 : 1 = P3V3_AUX ; 2 = IRQ_SMI_ACTIVE_N
R1459  Q_RES  10K 1% CHIP  pkg 0402LF  page 204 : 1 = P3V3_AUX ; 2 = IRQ_PCH_CPU_NMI_EVENT_R_N
R1460  Q_RES  2.2K 5% EMPTY  pkg 0402LF  page 241 : 1 = I3C_BMC_SWB_SDA ; 2 = P3V3_AUX
R1461  Q_RES  0 5% CHIP  pkg 0402LF  page 185 : 1 = FM_EUP_LOT6_N ; 2 = FM_SUSACK_N
R1462  Q_RES  1K 1% CHIP  pkg 0402LF  page 208 : 1 = PD_CK440_SBI_CLK ; 2 = GND
R1463  Q_RES  0 5% CHIP  pkg 0402LF  page 189 : 1 = P1V05_PCH_AUX ; 2 = P1V05_PCH_PLL_AUX
R1464  Q_RES  0 5% CHIP  pkg 0402LF  page 189 : 1 = P1V8_PCH_AUX ; 2 = P1V8_PCH_PLL_AUX
R1465  Q_RES  10K 1% EMPTY  pkg 0402LF  page 215 : 1 = P3V3_AUX ; 2 = IRQ_BMC_CPU_NMI_R1
R1467  Q_RES  4.7K 1% EMPTY  pkg 0402LF  page 213 : 1 = P3V3_AUX ; 2 = SMB_1_PLD_3V3AUX_SCL_R1
R1469  Q_RES  33.2 1% CHIP  pkg 0402LF  page 223 : 1 = RST_PLTRST_PLD_B_N ; 2 = RST_PLTRST_B_N
R1470  Q_RES  33.2 1% CHIP  pkg 0402LF  page 223 : 1 = RST_PLTRST_PLD_B_N ; 2 = RST_PLTRST_B_MUX_N
R1471  Q_RES  4.75K 1% CHIP  pkg 0402LF  page 208 : 1 = P3V3_AUX ; 2 = FM_CLK_CK440_SS_EN
R1472  Q_RES  33.2 1% CHIP  pkg 0402LF  page 131 : 1 = JTAG_DBP_PRESENT_R_N ; 2 = FM_BMC_DBP_PRESENT_R_N
R1473  Q_RES  1K 1% CHIP  pkg 0402LF  page 220 : 1 = FM_RST_PERST_BIT1 ; 2 = P3V3_AUX
R1474  Q_RES  1K 1% CHIP  pkg 0402LF  page 220 : 1 = FM_RST_PERST_BIT2 ; 2 = P3V3_AUX
R1475  Q_RES  1K 1% EMPTY  pkg 0402LF  page 200 : 1 = P3V3_AUX ; 2 = FM_PCH_RING_OSC_BYPASS_MGPIO_TE
R1476  Q_RES  1K 1% CHIP  pkg 0402LF  page 200 : 1 = FM_PCH_RING_OSC_BYPASS_MGPIO_TE ; 2 = GND
R1477  Q_RES  1K 1% EMPTY  pkg 0402LF  page 200 : 1 = P3V3_AUX ; 2 = FM_PCH_XTAL_INPUT_MODE_MGPIO_TE
R1478  Q_RES  10K 1% CHIP  pkg 0402LF  page 200 : 1 = FM_PCH_XTAL_INPUT_MODE_MGPIO_TE ; 2 = GND
R1479  Q_RES  10 1% CHIP  pkg 0402LF  page 202 : 1 = ESPI_LFRAME_N_BMC_CS0_N ; 2 = ESPI_HOST_LPC_BMC_LFRAME_N
R1483  Q_RES  10K 1% EMPTY  pkg 0402LF  page 208 : 1 = P3V3_AUX ; 2 = FM_CK440Q_DEV_25M_EN
R1484  Q_RES  1K 1% EMPTY  pkg 0402LF  page 208 : 1 = FM_CK440Q_DEV_25M_EN ; 2 = GND
R1485  Q_RES  200 1% EMPTY  pkg 0402LF  page 182 : 1 = PVNN_TERM_CPU0 ; 2 = FM_PCH_TRIGGER0_R_N
R1486  Q_RES  200 1% EMPTY  pkg 0402LF  page 182 : 1 = PVNN_TERM_CPU0 ; 2 = FM_PCH_TRIGGER1_R_N
R1487  Q_RES  100 1% CHIP  pkg 0402LF  page 183 : 1 = FM_PCH_SATA_RAID_KEY ; 2 = GND
R1492  Q_RES  10K 1% CHIP  pkg 0402LF  page 220 : 1 = FM_DIS_PS_PWROK_DLY ; 2 = P3V3_AUX
R1493  Q_RES  1K 1% CHIP  pkg 0402LF  page 215 : 1 = P3V3_AUX ; 2 = PU_FORCE_PWRON
R1494  Q_RES  1K 1% EMPTY  pkg 0402LF  page 220 : 1 = FM_DIS_PS_PWROK_DLY ; 2 = GND
R1495  Q_RES  10K 1% CHIP  pkg 0402LF  page 215 : 1 = PD_FORCE_PWRON ; 2 = GND
R1496  Q_RES  10K 1% CHIP  pkg 0402LF  page 200 : 1 = P3V3_AUX ; 2 = FM_PCH_DFXTESTMODE
R1497  Q_RES  12K 1% EMPTY  pkg 0402LF  page 200 : 1 = FM_PCH_DFXTESTMODE ; 2 = GND
R1498  Q_RES  1K 1% EMPTY  pkg 0402LF  page 200 : 1 = P1V05_PCH_AUX ; 2 = FM_BIOS_ADV_FUNCTIONS
R1499  Q_RES  1K 1% CHIP  pkg 0402LF  page 200 : 1 = FM_BIOS_ADV_FUNCTIONS ; 2 = GND
R1500  Q_RES  4.75K 1% CHIP  pkg 0402LF  page 208 : 1 = PD_CK440_SBI_DATA_IN ; 2 = GND
R1502  Q_RES  4.75K 1% CHIP  pkg 0402LF  page 208 : 1 = FM_CLK_CK440_SS_EN ; 2 = GND
R1504  Q_RES  33.2 1% CHIP  pkg 0402LF  page 155 : 1 = RST_OCP_V3_1_BUF_N ; 2 = RST_PERST2_OCP_SFF_N
R1505  Q_RES  33.2 1% CHIP  pkg 0402LF  page 155 : 1 = RST_OCP_V3_1_BUF_N ; 2 = RST_PERST3_OCP_SFF_N
R1514  Q_RES  33.2 1% CHIP  pkg 0402LF  page 223 : 1 = RST_PCIE_CPU0_DEV_PERST_N ; 2 = RST_OCP_V3_1_N
